FILE_TYPE = MACRO_DRAWING;
SET COLOR_WIRE YELLOW;
SET COLOR_PROP ORANGE;
SET COLOR_DOT WHITE;
SET COLOR_ARC YELLOW;
SET COLOR_BODY GREEN;
SET COLOR_NOTE PURPLE;
SET PROP_DISPLAY VALUE;
SET PAGE_NUMBER P152;
FORCEADD QUANTA_TITLE_BLOCK_C..1
(0 0);
FORCEPROP 1 LAST CUSTOM_TXT_CDS <NAME_2>
J 0
(-3175 50);
FORCEPROP 1 LAST CUSTOM_TXT_CDS <NAME_1>
J 0
(-3175 175);
FORCEPROP 1 LAST CUSTOM_TXT_CDS <Q_NUMBER>
J 0
(-1403 103);
DISPLAY 1.212766 (-1403 103);
FORCEPROP 1 LAST CUSTOM_TXT_CDS <Q_PROJ>
J 0
(-2382 102);
DISPLAY 1.212766 (-2382 102);
FORCEPROP 1 LAST CUSTOM_TXT_CDS <Q_REV>
J 0
(-184 103);
DISPLAY 1.212766 (-184 103);
FORCEPROP 1 LAST CUSTOM_TXT_CDS <CON_LAST_MODIFIED>
J 0
(-1885 15);
DISPLAY 0.978723 (-1885 15);
FORCEPROP 1 LAST CUSTOM_TXT_CDS <CON_PAGE_NUM> OF <CON_TOTAL_PAGES>
J 0
(-446 18);
DISPLAY 0.978723 (-446 18);
FORCEPROP 1 LAST Q_TITLE Blank
J 0
(-9250 75);
DISPLAY 2.446809 (-9250 75);
PAINT GREEN (-9250 75);
FORCEPROP 1 LAST CDS_LMAN_SYM_OUTLINE -9475,6775,100,-125
J 0
(0 0);
DISPLAY 0.468085 (0 0);
PAINT GREEN (0 0);
DISPLAY INVISIBLE (0 0);
FORCEPROP 2 LAST CDS_LIB pure_quanta
J 0
(0 0);
DISPLAY INVISIBLE (0 0);
FORCEPROP 2 LAST PAGE_BORDER TRUE
J 0
(-7890 5250);
DISPLAY 0.638298 (-7890 5250);
PAINT PINK (-7890 5250);
DISPLAY INVISIBLE (-7890 5250);
FORCEPROP 2 LAST CDS_XR_PAGE_TITLE CR-175 : @T6G_MB_LIB.T6G(SCH_1):PAGE175
J 0
(-7890 5250);
DISPLAY 0.638298 (-7890 5250);
PAINT PINK (-7890 5250);
DISPLAY INVISIBLE (-7890 5250);
FORCEPROP 2 LAST CUSTOM_TXT_CDS <XR_PAGE_TITLE>
J 0
(-7890 5250);
DISPLAY 0.638298 (-7890 5250);
PAINT PINK (-7890 5250);
DISPLAY INVISIBLE (-7890 5250);
FORCEPROP 1 LAST COMMENT_BODY TRUE
J 0
(12 -13);
DISPLAY 0.978723 (12 -13);
PAINT GREEN (12 -13);
DISPLAY INVISIBLE (12 -13);
FORCEPROP 1 LAST Q_DEPT BU9
J 1
(-3763 49);
DISPLAY 1.957447 (-3763 49);
PAINT GREEN (-3763 49);
DISPLAY INVISIBLE (-3763 49);
FORCEPROP 0 LAST CDS_CON_LAST_MODIFIED Thu Aug 24 10:14:54 2023
J 0
(-1885 15);
DISPLAY INVISIBLE (-1885 15);
QUIT
